(kicad_pcb
	(version 20241229)
	(generator "pcbnew")
	(generator_version "9.0")
	(general
		(thickness 1.62)
		(legacy_teardrops no)
	)
	(paper "A3")
	(title_block
		(title "COM Express 7 Baseboard")
		(date "2025-02-04")
		(rev "1.1.2")
		(company "Antmicro Ltd")
		(comment 1 "www.antmicro.com")
		(comment 9 "footprints 632-635 of 802")
	)
	(layers
		(0 "F.Cu" signal)
		(4 "In1.Cu" signal)
		(6 "In2.Cu" signal)
		(8 "In3.Cu" signal)
		(10 "In4.Cu" signal)
		(12 "In5.Cu" signal)
		(14 "In6.Cu" signal)
		(2 "B.Cu" signal)
		(9 "F.Adhes" user "F.Adhesive")
		(11 "B.Adhes" user "B.Adhesive")
		(13 "F.Paste" user)
		(15 "B.Paste" user)
		(5 "F.SilkS" user "F.Silkscreen")
		(7 "B.SilkS" user "B.Silkscreen")
		(1 "F.Mask" user)
		(3 "B.Mask" user)
		(17 "Dwgs.User" user "User.Drawings")
		(19 "Cmts.User" user "User.Comments")
		(21 "Eco1.User" user "User.Eco1")
		(23 "Eco2.User" user "User.Eco2")
		(25 "Edge.Cuts" user)
		(27 "Margin" user)
		(31 "F.CrtYd" user "F.Courtyard")
		(29 "B.CrtYd" user "B.Courtyard")
		(35 "F.Fab" user)
		(33 "B.Fab" user)
	)
	(footprint "antmicro-footprints:USON-10_2.5x1mm_P0.5mm"
		(layer "B.Cu")
		(at 314.75 160.91 180)
		(descr "USON-10 2.5x1mm_ Pitch 0.5mm")
		(tags "USON-10 2.5x1mm Pitch 0.5mm")
		(property "Reference" "U14"
			(at 0.85 1.1 90)
			(layer "B.SilkS")
			(effects
				(font
					(size 0.7 0.7)
					(thickness 0.15)
				)
				(justify left bottom mirror)
			)
		)
		(property "Value" "ESD204DQAR"
			(at 0.018 -2.499 0)
			(layer "B.Fab")
			(effects
				(font
					(size 0.7 0.7)
					(thickness 0.15)
				)
				(justify left bottom mirror)
			)
		)
		(property "Datasheet" "https://www.ti.com/lit/ds/symlink/esd204.pdf?ts=1706004844383&ref_url=https%253A%252F%252Fwww.ti.com%252Finterface%252Fdiodes%252Fesd-protection-diodes%252Fproducts.html"
			(at 0 0 180)
			(layer "F.Fab")
			(hide yes)
			(effects
				(font
					(size 1.27 1.27)
					(thickness 0.15)
				)
			)
		)
		(property "Author" "Antmicro"
			(at 625.5 319.02 0)
			(layer "B.Fab")
			(hide yes)
			(effects
				(font
					(size 1 1)
					(thickness 0.15)
				)
				(justify mirror)
			)
		)
		(property "License" "Apache-2.0"
			(at 625.5 319.02 0)
			(layer "B.Fab")
			(hide yes)
			(effects
				(font
					(size 1 1)
					(thickness 0.15)
				)
				(justify mirror)
			)
		)
		(property "MPN" "ESD204DQAR"
			(at 625.5 319.02 0)
			(layer "B.Fab")
			(hide yes)
			(effects
				(font
					(size 1 1)
					(thickness 0.15)
				)
				(justify mirror)
			)
		)
		(property "Manufacturer" "Texas Instruments"
			(at 625.5 319.02 0)
			(layer "B.Fab")
			(hide yes)
			(effects
				(font
					(size 1 1)
					(thickness 0.15)
				)
				(justify mirror)
			)
		)
		(sheetname "Backplane")
		(sheetfile "backplane.kicad_sch")
		(attr smd)
		(fp_line
			(start -0.5 1.401)
			(end 0.498 1.401)
			(stroke
				(width 0.15)
				(type solid)
			)
			(layer "B.SilkS")
		)
		(fp_line
			(start -0.5 -1.398)
			(end 0.498 -1.398)
			(stroke
				(width 0.15)
				(type solid)
			)
			(layer "B.SilkS")
		)
		(fp_circle
			(center -0.68 1.27)
			(end -0.63 1.27)
			(stroke
				(width 0.15)
				(type solid)
			)
			(fill yes)
			(layer "B.SilkS")
		)
		(fp_rect
			(start -0.8 1.5)
			(end 0.8 -1.499)
			(stroke
				(width 0.05)
				(type solid)
			)
			(fill no)
			(layer "B.CrtYd")
		)
		(fp_line
			(start 0.498 -1.249)
			(end 0.498 1.25)
			(stroke
				(width 0.15)
				(type solid)
			)
			(layer "B.Fab")
		)
		(fp_line
			(start 0.498 -1.249)
			(end -0.5 -1.249)
			(stroke
				(width 0.15)
				(type solid)
			)
			(layer "B.Fab")
		)
		(fp_line
			(start -0.25 1.25)
			(end 0.498 1.25)
			(stroke
				(width 0.15)
				(type solid)
			)
			(layer "B.Fab")
		)
		(fp_line
			(start -0.5 1)
			(end -0.25 1.25)
			(stroke
				(width 0.15)
				(type solid)
			)
			(layer "B.Fab")
		)
		(fp_line
			(start -0.5 -1.249)
			(end -0.5 1)
			(stroke
				(width 0.15)
				(type solid)
			)
			(layer "B.Fab")
		)
		(pad "1" smd roundrect
			(at -0.387 1 270)
			(size 0.25 0.55)
			(layers "B.Cu" "B.Mask" "B.Paste")
			(roundrect_rratio 0.25)
			(net 866 "/Backplane/PCIe_{x2}.TX0+")
			(pintype "passive")
			(teardrops
				(best_length_ratio 0.2)
				(max_length 1)
				(best_width_ratio 0.9)
				(max_width 2)
				(curved_edges yes)
				(filter_ratio 0.9)
				(enabled yes)
				(allow_two_segments yes)
				(prefer_zone_connections yes)
			)
		)
		(pad "2" smd roundrect
			(at -0.387 0.5 270)
			(size 0.25 0.55)
			(layers "B.Cu" "B.Mask" "B.Paste")
			(roundrect_rratio 0.25)
			(net 867 "/Backplane/PCIe_{x2}.TX0-")
			(pintype "passive")
			(teardrops
				(best_length_ratio 0.2)
				(max_length 1)
				(best_width_ratio 0.9)
				(max_width 2)
				(curved_edges yes)
				(filter_ratio 0.9)
				(enabled yes)
				(allow_two_segments yes)
				(prefer_zone_connections yes)
			)
		)
		(pad "3" smd roundrect
			(at -0.387 0 270)
			(size 0.4 0.55)
			(layers "B.Cu" "B.Mask" "B.Paste")
			(roundrect_rratio 0.25)
			(net 1 "GND")
			(pintype "power_in")
			(teardrops
				(best_length_ratio 0.2)
				(max_length 1)
				(best_width_ratio 0.9)
				(max_width 2)
				(curved_edges yes)
				(filter_ratio 0.9)
				(enabled yes)
				(allow_two_segments yes)
				(prefer_zone_connections yes)
			)
		)
		(pad "4" smd roundrect
			(at -0.387 -0.498 270)
			(size 0.25 0.55)
			(layers "B.Cu" "B.Mask" "B.Paste")
			(roundrect_rratio 0.25)
			(net 868 "/Backplane/PCIe_{x2}.TX1+")
			(pintype "passive")
			(teardrops
				(best_length_ratio 0.2)
				(max_length 1)
				(best_width_ratio 0.9)
				(max_width 2)
				(curved_edges yes)
				(filter_ratio 0.9)
				(enabled yes)
				(allow_two_segments yes)
				(prefer_zone_connections yes)
			)
		)
		(pad "5" smd roundrect
			(at -0.387 -0.998 270)
			(size 0.25 0.55)
			(layers "B.Cu" "B.Mask" "B.Paste")
			(roundrect_rratio 0.25)
			(net 869 "/Backplane/PCIe_{x2}.TX1-")
			(pintype "passive")
			(teardrops
				(best_length_ratio 0.2)
				(max_length 1)
				(best_width_ratio 0.9)
				(max_width 2)
				(curved_edges yes)
				(filter_ratio 0.9)
				(enabled yes)
				(allow_two_segments yes)
				(prefer_zone_connections yes)
			)
		)
		(pad "6" smd roundrect
			(at 0.385 -0.998 270)
			(size 0.25 0.55)
			(layers "B.Cu" "B.Mask" "B.Paste")
			(roundrect_rratio 0.25)
			(net 869 "/Backplane/PCIe_{x2}.TX1-")
			(pintype "passive")
			(teardrops
				(best_length_ratio 0.2)
				(max_length 1)
				(best_width_ratio 0.9)
				(max_width 2)
				(curved_edges yes)
				(filter_ratio 0.9)
				(enabled yes)
				(allow_two_segments yes)
				(prefer_zone_connections yes)
			)
		)
		(pad "7" smd roundrect
			(at 0.385 -0.498 270)
			(size 0.25 0.55)
			(layers "B.Cu" "B.Mask" "B.Paste")
			(roundrect_rratio 0.25)
			(net 868 "/Backplane/PCIe_{x2}.TX1+")
			(pintype "passive")
			(teardrops
				(best_length_ratio 0.2)
				(max_length 1)
				(best_width_ratio 0.9)
				(max_width 2)
				(curved_edges yes)
				(filter_ratio 0.9)
				(enabled yes)
				(allow_two_segments yes)
				(prefer_zone_connections yes)
			)
		)
		(pad "8" smd roundrect
			(at 0.385 0 270)
			(size 0.4 0.55)
			(layers "B.Cu" "B.Mask" "B.Paste")
			(roundrect_rratio 0.25)
			(net 1 "GND")
			(pintype "passive")
			(teardrops
				(best_length_ratio 0.2)
				(max_length 1)
				(best_width_ratio 0.9)
				(max_width 2)
				(curved_edges yes)
				(filter_ratio 0.9)
				(enabled yes)
				(allow_two_segments yes)
				(prefer_zone_connections yes)
			)
		)
		(pad "9" smd roundrect
			(at 0.385 0.5 270)
			(size 0.25 0.55)
			(layers "B.Cu" "B.Mask" "B.Paste")
			(roundrect_rratio 0.25)
			(net 867 "/Backplane/PCIe_{x2}.TX0-")
			(pintype "passive")
			(teardrops
				(best_length_ratio 0.2)
				(max_length 1)
				(best_width_ratio 0.9)
				(max_width 2)
				(curved_edges yes)
				(filter_ratio 0.9)
				(enabled yes)
				(allow_two_segments yes)
				(prefer_zone_connections yes)
			)
		)
		(pad "10" smd roundrect
			(at 0.385 1 270)
			(size 0.25 0.55)
			(layers "B.Cu" "B.Mask" "B.Paste")
			(roundrect_rratio 0.25)
			(net 866 "/Backplane/PCIe_{x2}.TX0+")
			(pintype "passive")
			(teardrops
				(best_length_ratio 0.2)
				(max_length 1)
				(best_width_ratio 0.9)
				(max_width 2)
				(curved_edges yes)
				(filter_ratio 0.9)
				(enabled yes)
				(allow_two_segments yes)
				(prefer_zone_connections yes)
			)
		)
	)
	(footprint "antmicro-footprints:C_0603_1608Metric"
		(layer "B.Cu")
		(at 104.65 168.76 180)
		(descr "Capacitor SMD 0603")
		(tags "capacitor 0603")
		(property "Reference" "C37"
			(at -3.29 -0.14 0)
			(layer "B.SilkS")
			(effects
				(font
					(size 0.7 0.7)
					(thickness 0.15)
				)
				(justify left bottom mirror)
			)
		)
		(property "Value" "C_22u_16V_0603"
			(at -1.42757 -1.770288 0)
			(layer "B.Fab")
			(effects
				(font
					(size 0.7 0.7)
					(thickness 0.15)
				)
				(justify left bottom mirror)
			)
		)
		(property "Datasheet" "https://product.samsungsem.com/mlcc/CL10A226MO7JZN.do"
			(at 0 0 180)
			(layer "F.Fab")
			(hide yes)
			(effects
				(font
					(size 1.27 1.27)
					(thickness 0.15)
				)
			)
		)
		(property "Author" "Antmicro"
			(at 209.3 337.52 0)
			(layer "B.Fab")
			(hide yes)
			(effects
				(font
					(size 1 1)
					(thickness 0.15)
				)
				(justify mirror)
			)
		)
		(property "Dielectric" ""
			(at 209.3 337.52 0)
			(layer "B.Fab")
			(hide yes)
			(effects
				(font
					(size 1 1)
					(thickness 0.15)
				)
				(justify mirror)
			)
		)
		(property "License" "Apache-2.0"
			(at 209.3 337.52 0)
			(layer "B.Fab")
			(hide yes)
			(effects
				(font
					(size 1 1)
					(thickness 0.15)
				)
				(justify mirror)
			)
		)
		(property "MPN" "CL10A226MO7JZNC"
			(at 209.3 337.52 0)
			(layer "B.Fab")
			(hide yes)
			(effects
				(font
					(size 1 1)
					(thickness 0.15)
				)
				(justify mirror)
			)
		)
		(property "Manufacturer" "Samsung Electro-Mechanics"
			(at 209.3 337.52 0)
			(layer "B.Fab")
			(hide yes)
			(effects
				(font
					(size 1 1)
					(thickness 0.15)
				)
				(justify mirror)
			)
		)
		(property "Public" "False"
			(at 209.3 337.52 0)
			(layer "B.Fab")
			(hide yes)
			(effects
				(font
					(size 1 1)
					(thickness 0.15)
				)
				(justify mirror)
			)
		)
		(property "Val" "22u"
			(at 209.3 337.52 0)
			(layer "B.Fab")
			(hide yes)
			(effects
				(font
					(size 1 1)
					(thickness 0.15)
				)
				(justify mirror)
			)
		)
		(property "Voltage" "16V"
			(at 209.3 337.52 0)
			(layer "B.Fab")
			(hide yes)
			(effects
				(font
					(size 1 1)
					(thickness 0.15)
				)
				(justify mirror)
			)
		)
		(sheetname "OCuLink")
		(sheetfile "oculink.kicad_sch")
		(attr smd)
		(fp_line
			(start 0.15 0.4)
			(end -0.15 0.4)
			(stroke
				(width 0.15)
				(type solid)
			)
			(layer "B.SilkS")
		)
		(fp_line
			(start 0.15 -0.4)
			(end -0.15 -0.4)
			(stroke
				(width 0.15)
				(type solid)
			)
			(layer "B.SilkS")
		)
		(fp_rect
			(start -1.25 0.65)
			(end 1.25 -0.65)
			(stroke
				(width 0.05)
				(type solid)
			)
			(fill no)
			(layer "B.CrtYd")
		)
		(fp_rect
			(start -0.8 0.4)
			(end 0.8 -0.4)
			(stroke
				(width 0.15)
				(type solid)
			)
			(fill no)
			(layer "B.Fab")
		)
		(pad "1" smd roundrect
			(at -0.7 0 180)
			(size 0.8 1)
			(layers "B.Cu" "B.Mask" "B.Paste")
			(roundrect_rratio 0.2)
			(net 1 "GND")
			(pintype "passive")
			(teardrops
				(best_length_ratio 0.2)
				(max_length 1)
				(best_width_ratio 0.9)
				(max_width 2)
				(curved_edges yes)
				(filter_ratio 0.9)
				(enabled yes)
				(allow_two_segments yes)
				(prefer_zone_connections yes)
			)
		)
		(pad "2" smd roundrect
			(at 0.7 0 180)
			(size 0.8 1)
			(layers "B.Cu" "B.Mask" "B.Paste")
			(roundrect_rratio 0.2)
			(net 60 "/OCuLink/V_{ACT_RX}0")
			(pintype "passive")
			(teardrops
				(best_length_ratio 0.2)
				(max_length 1)
				(best_width_ratio 0.9)
				(max_width 2)
				(curved_edges yes)
				(filter_ratio 0.9)
				(enabled yes)
				(allow_two_segments yes)
				(prefer_zone_connections yes)
			)
		)
	)
	(footprint "antmicro-footprints:TP_SMD_0.75mm"
		(layer "B.Cu")
		(at 139.95 167.21 180)
		(property "Reference" "TP6"
			(at 0.4 -0.5 0)
			(layer "B.SilkS")
			(effects
				(font
					(size 0.7 0.7)
					(thickness 0.15)
				)
				(justify left bottom mirror)
			)
		)
		(property "Value" "TP_0.75mm_SMD"
			(at 0 -1.2 0)
			(layer "B.Fab")
			(effects
				(font
					(size 0.7 0.7)
					(thickness 0.15)
				)
				(justify left bottom mirror)
			)
		)
		(property "Author" "Antmicro"
			(at 279.9 334.42 0)
			(layer "B.Fab")
			(hide yes)
			(effects
				(font
					(size 1 1)
					(thickness 0.15)
				)
				(justify mirror)
			)
		)
		(property "License" "Apache-2.0"
			(at 279.9 334.42 0)
			(layer "B.Fab")
			(hide yes)
			(effects
				(font
					(size 1 1)
					(thickness 0.15)
				)
				(justify mirror)
			)
		)
		(property "MPN" ""
			(at 279.9 334.42 0)
			(layer "B.Fab")
			(hide yes)
			(effects
				(font
					(size 1 1)
					(thickness 0.15)
				)
				(justify mirror)
			)
		)
		(property "Manufacturer" ""
			(at 279.9 334.42 0)
			(layer "B.Fab")
			(hide yes)
			(effects
				(font
					(size 1 1)
					(thickness 0.15)
				)
				(justify mirror)
			)
		)
		(property "Public" "False"
			(at 279.9 334.42 0)
			(layer "B.Fab")
			(hide yes)
			(effects
				(font
					(size 1 1)
					(thickness 0.15)
				)
				(justify mirror)
			)
		)
		(sheetname "2xSFP+")
		(sheetfile "2xSFP+.kicad_sch")
		(attr exclude_from_pos_files exclude_from_bom)
		(fp_circle
			(center 0 0)
			(end 0.475 0)
			(stroke
				(width 0.05)
				(type default)
			)
			(fill no)
			(layer "B.CrtYd")
		)
		(pad "1" smd circle
			(at 0 0 180)
			(size 0.75 0.75)
			(layers "B.Cu" "B.Mask")
			(net 896 "Net-(J2B-RX_{LOS})")
			(pinfunction "1")
			(pintype "passive")
			(teardrops
				(best_length_ratio 0.4)
				(max_length 1)
				(best_width_ratio 0.9)
				(max_width 2)
				(curved_edges yes)
				(filter_ratio 0.9)
				(enabled yes)
				(allow_two_segments yes)
				(prefer_zone_connections yes)
			)
		)
	)
	(footprint "antmicro-footprints:C_0402_1005Metric"
		(layer "B.Cu")
		(at 104.28 82.42 -90)
		(descr "Capacitor SMD 0402")
		(tags "capacitor SMD 0402")
		(property "Reference" "C29"
			(at -1.11 0.48 90)
			(layer "B.SilkS")
			(effects
				(font
					(size 0.7 0.7)
					(thickness 0.15)
				)
				(justify left bottom mirror)
			)
		)
		(property "Value" "C_100n_0402"
			(at -1.022927 -2.155213 90)
			(layer "B.Fab")
			(effects
				(font
					(size 0.7 0.7)
					(thickness 0.15)
				)
				(justify left bottom mirror)
			)
		)
		(property "Datasheet" "https://www.murata.com/products/productdetail?partno=GRM155R61H104KE14%23"
			(at 0 0 270)
			(layer "F.Fab")
			(hide yes)
			(effects
				(font
					(size 1.27 1.27)
					(thickness 0.15)
				)
			)
		)
		(property "Author" "Antmicro"
			(at 21.86 186.7 0)
			(layer "B.Fab")
			(hide yes)
			(effects
				(font
					(size 1 1)
					(thickness 0.15)
				)
				(justify mirror)
			)
		)
		(property "Dielectric" "X5R"
			(at 21.86 186.7 0)
			(layer "B.Fab")
			(hide yes)
			(effects
				(font
					(size 1 1)
					(thickness 0.15)
				)
				(justify mirror)
			)
		)
		(property "License" "Apache-2.0"
			(at 21.86 186.7 0)
			(layer "B.Fab")
			(hide yes)
			(effects
				(font
					(size 1 1)
					(thickness 0.15)
				)
				(justify mirror)
			)
		)
		(property "MPN" "GRM155R61H104KE14D"
			(at 21.86 186.7 0)
			(layer "B.Fab")
			(hide yes)
			(effects
				(font
					(size 1 1)
					(thickness 0.15)
				)
				(justify mirror)
			)
		)
		(property "Manufacturer" "Murata"
			(at 21.86 186.7 0)
			(layer "B.Fab")
			(hide yes)
			(effects
				(font
					(size 1 1)
					(thickness 0.15)
				)
				(justify mirror)
			)
		)
		(property "Public" "False"
			(at 21.86 186.7 0)
			(layer "B.Fab")
			(hide yes)
			(effects
				(font
					(size 1 1)
					(thickness 0.15)
				)
				(justify mirror)
			)
		)
		(property "Val" "100n"
			(at 21.86 186.7 0)
			(layer "B.Fab")
			(hide yes)
			(effects
				(font
					(size 1 1)
					(thickness 0.15)
				)
				(justify mirror)
			)
		)
		(property "Voltage" "50V"
			(at 21.86 186.7 0)
			(layer "B.Fab")
			(hide yes)
			(effects
				(font
					(size 1 1)
					(thickness 0.15)
				)
				(justify mirror)
			)
		)
		(sheetname "USB-C console")
		(sheetfile "usb-c_console.kicad_sch")
		(attr smd)
		(fp_rect
			(start -0.925 0.47)
			(end 0.925 -0.47)
			(stroke
				(width 0.05)
				(type default)
			)
			(fill no)
			(layer "B.CrtYd")
		)
		(fp_line
			(start -0.494 0.25)
			(end -0.494 -0.248)
			(stroke
				(width 0.15)
				(type solid)
			)
			(layer "B.Fab")
		)
		(fp_line
			(start 0.504 0.25)
			(end -0.494 0.25)
			(stroke
				(width 0.15)
				(type solid)
			)
			(layer "B.Fab")
		)
		(fp_line
			(start -0.494 -0.248)
			(end 0.504 -0.248)
			(stroke
				(width 0.15)
				(type solid)
			)
			(layer "B.Fab")
		)
		(fp_line
			(start 0.504 -0.248)
			(end 0.504 0.25)
			(stroke
				(width 0.15)
				(type solid)
			)
			(layer "B.Fab")
		)
		(pad "1" smd roundrect
			(at -0.48 0 270)
			(size 0.59 0.64)
			(layers "B.Cu" "B.Mask" "B.Paste")
			(roundrect_rratio 0.25)
			(net 54 "/USB-C console/SH")
			(pintype "passive")
			(teardrops
				(best_length_ratio 0.2)
				(max_length 1)
				(best_width_ratio 0.9)
				(max_width 2)
				(curved_edges yes)
				(filter_ratio 0.9)
				(enabled yes)
				(allow_two_segments yes)
				(prefer_zone_connections yes)
			)
		)
		(pad "2" smd roundrect
			(at 0.48 0 270)
			(size 0.59 0.64)
			(layers "B.Cu" "B.Mask" "B.Paste")
			(roundrect_rratio 0.25)
			(net 1 "GND")
			(pintype "passive")
			(teardrops
				(best_length_ratio 0.2)
				(max_length 1)
				(best_width_ratio 0.9)
				(max_width 2)
				(curved_edges yes)
				(filter_ratio 0.9)
				(enabled yes)
				(allow_two_segments yes)
				(prefer_zone_connections yes)
			)
		)
	)
)
